# TIMECARD (Time Appliance Project (Time Card)) — schematic netlist excerpt (pin names and nets, part order shuffled) for the footprints in the layout excerpt that follows; sources: Cadence DE-HDL packaged netlist, KiCad conversion of R4006-B0001-02_R01.brd

R278  RESISTOR  100OHM 1%  pkg SMC_0402R_H016  page 13 : \1\ = MHZ200CLKP_CLKIN ; \2\ = MHZ200CLKN_CLKIN
C283  CAPACITOR  10UF 25V 20%  pkg SMC_0805R_H057  page 21 : \1\ = XP5R0V_MAC ; \2\ = SG

(kicad_pcb
	(version 20260206)
	(generator "pcbnew")
	(generator_version "10.0")
	(general
		(thickness 1.6)
		(legacy_teardrops no)
	)
	(paper "A4")
	(title_block
		(title "timecard-production-celestica-r4006 — R4006-B0001-02_R01.brd")
		(comment 1 "Time Appliance Project (Time Card) / footprints 765-766 of 1113")
	)
	(layers
		(0 "F.Cu" signal "TOP")
		(4 "In1.Cu" signal "L02_GND1")
		(6 "In2.Cu" signal "L03_SIG1")
		(8 "In3.Cu" signal "L04_GND2")
		(10 "In4.Cu" signal "L05_VCC1")
		(12 "In5.Cu" signal "L06_VCC2")
		(14 "In6.Cu" signal "L07_GND3")
		(16 "In7.Cu" signal "L08_SIG2")
		(18 "In8.Cu" signal "L09_GND4")
		(2 "B.Cu" signal "BOTTOM")
		(9 "F.Adhes" user "F.Adhesive")
		(11 "B.Adhes" user "B.Adhesive")
		(13 "F.Paste" user "Package Geometry/Pastemask Top")
		(15 "B.Paste" user "Package Geometry/Pastemask Bottom")
		(5 "F.SilkS" user "Ref Des/Silkscreen Top")
		(7 "B.SilkS" user "Ref Des/Silkscreen Bottom")
		(1 "F.Mask" user "Board Geometry/Soldermask Top")
		(3 "B.Mask" user "Board Geometry/Soldermask Bottom")
		(17 "Dwgs.User" user "User.Drawings")
		(19 "Cmts.User" user "User.Comments")
		(21 "Eco1.User" user "User.Eco1")
		(23 "Eco2.User" user "User.Eco2")
		(25 "Edge.Cuts" user "Board Geometry/Outline")
		(27 "Margin" user)
		(31 "F.CrtYd" user "Package Geometry/Place Bound Top")
		(29 "B.CrtYd" user "Package Geometry/Place Bound Bottom")
		(35 "F.Fab" user "Ref Des/Assembly Top")
		(33 "B.Fab" user "Ref Des/Assembly Bottom")
	)
	(footprint ""
		(layer "B.Cu")
		(at 114.347244 -36.823142 180)
		(property "Reference" "R278"
			(at -0.079756 0.991108 0)
			(unlocked yes)
			(layer "B.SilkS")
			(effects
				(font
					(size 0.635 0.4064)
					(thickness 0.1524)
				)
				(justify mirror)
			)
		)
		(property "Value" "VAL*"
			(at 0 3.718306 180)
			(unlocked yes)
			(layer "B.Fab")
			(hide yes)
			(effects
				(font
					(size 0.7874 0.5842)
					(thickness 0.127)
				)
				(justify mirror)
			)
		)
		(property "Tolerance" "TOL*"
			(at 0 4.861306 180)
			(unlocked yes)
			(layer "Cmts.User")
			(hide yes)
			(effects
				(font
					(size 0.7874 0.5842)
					(thickness 0.127)
				)
				(justify mirror)
			)
		)
		(property "User Part Number" "PARTNUM*"
			(at 0 2.575306 180)
			(unlocked yes)
			(layer "Cmts.User")
			(hide yes)
			(effects
				(font
					(size 0.7874 0.5842)
					(thickness 0.127)
				)
				(justify mirror)
			)
		)
		(property "Device Type" "RESISTOR-G155-11000-01,100OHM,A"
			(at 0 1.432306 180)
			(unlocked yes)
			(layer "B.Fab")
			(hide yes)
			(effects
				(font
					(size 0.7874 0.5842)
					(thickness 0.127)
				)
				(justify mirror)
			)
		)
		(duplicate_pad_numbers_are_jumpers no)
		(fp_line
			(start 0.970026 0.4699)
			(end 0.970026 -0.4699)
			(stroke
				(width 0.1)
				(type default)
			)
			(layer "B.SilkS")
		)
		(fp_line
			(start 0.970026 -0.4699)
			(end -0.970026 -0.4699)
			(stroke
				(width 0.1)
				(type default)
			)
			(layer "B.SilkS")
		)
		(fp_line
			(start -0.970026 0.4699)
			(end 0.970026 0.4699)
			(stroke
				(width 0.1)
				(type default)
			)
			(layer "B.SilkS")
		)
		(fp_line
			(start -0.970026 -0.4699)
			(end -0.970026 0.4699)
			(stroke
				(width 0.1)
				(type default)
			)
			(layer "B.SilkS")
		)
		(fp_poly
			(pts
				(xy 0.970026 0.4699) (xy -0.970026 0.4699) (xy -0.970026 -0.4699) (xy 0.970026 -0.4699)
			)
			(stroke
				(width 0)
				(type default)
			)
			(fill no)
			(layer "B.CrtYd")
		)
		(fp_line
			(start 0.508 0.3048)
			(end 0.508 -0.3048)
			(stroke
				(width 0.1)
				(type default)
			)
			(layer "B.Fab")
		)
		(fp_line
			(start 0.508 -0.3048)
			(end -0.508 -0.3048)
			(stroke
				(width 0.1)
				(type default)
			)
			(layer "B.Fab")
		)
		(fp_line
			(start -0.508 0.3048)
			(end 0.508 0.3048)
			(stroke
				(width 0.1)
				(type default)
			)
			(layer "B.Fab")
		)
		(fp_line
			(start -0.508 -0.3048)
			(end -0.508 0.3048)
			(stroke
				(width 0.1)
				(type default)
			)
			(layer "B.Fab")
		)
		(pad "1" smd circle
			(at 0.500126 0)
			(size 0.635 0.635)
			(layers "B.Cu" "B.Mask" "B.Paste")
			(net "MHZ200CLKP_CLKIN")
		)
		(pad "2" smd circle
			(at -0.500126 0)
			(size 0.635 0.635)
			(layers "B.Cu" "B.Mask" "B.Paste")
			(net "MHZ200CLKN_CLKIN")
		)
	)
	(footprint ""
		(layer "B.Cu")
		(at 78.994 -73.152 -90)
		(property "Reference" "C283"
			(at -3.683 0.42037 270)
			(unlocked yes)
			(layer "B.SilkS")
			(effects
				(font
					(size 0.7874 0.5842)
					(thickness 0.1524)
				)
				(justify mirror)
			)
		)
		(property "Value" "VAL*"
			(at -0.0762 3.134106 270)
			(unlocked yes)
			(layer "B.Fab")
			(hide yes)
			(effects
				(font
					(size 0.7874 0.5842)
					(thickness 0.1524)
				)
				(justify mirror)
			)
		)
		(property "Device Type" "CAPACITOR-G107-0F106-EM,10UF,2A"
			(at -0.0508 2.194306 270)
			(unlocked yes)
			(layer "B.Fab")
			(hide yes)
			(effects
				(font
					(size 0.7874 0.5842)
					(thickness 0.1524)
				)
				(justify mirror)
			)
		)
		(property "User Part Number" "PARTNUM*"
			(at -0.1016 5.013706 270)
			(unlocked yes)
			(layer "Cmts.User")
			(hide yes)
			(effects
				(font
					(size 0.7874 0.5842)
					(thickness 0.1524)
				)
				(justify mirror)
			)
		)
		(property "Tolerance" "TOL*"
			(at -0.0762 4.048506 270)
			(unlocked yes)
			(layer "Cmts.User")
			(hide yes)
			(effects
				(font
					(size 0.7874 0.5842)
					(thickness 0.1524)
				)
				(justify mirror)
			)
		)
		(duplicate_pad_numbers_are_jumpers no)
		(fp_line
			(start -1.5748 0.9398)
			(end -1.5748 -0.9398)
			(stroke
				(width 0.1)
				(type default)
			)
			(layer "B.SilkS")
		)
		(fp_line
			(start 1.5748 0.9398)
			(end -1.5748 0.9398)
			(stroke
				(width 0.1)
				(type default)
			)
			(layer "B.SilkS")
		)
		(fp_line
			(start -1.5748 -0.9398)
			(end 1.5748 -0.9398)
			(stroke
				(width 0.1)
				(type default)
			)
			(layer "B.SilkS")
		)
		(fp_line
			(start 1.5748 -0.9398)
			(end 1.5748 0.9398)
			(stroke
				(width 0.1)
				(type default)
			)
			(layer "B.SilkS")
		)
		(fp_rect
			(start 1.5748 0.9398)
			(end -1.5748 -0.9398)
			(stroke
				(width 0)
				(type default)
			)
			(fill no)
			(layer "B.CrtYd")
		)
		(fp_line
			(start -1.016 0.635)
			(end -1.016 -0.635)
			(stroke
				(width 0.1)
				(type default)
			)
			(layer "B.Fab")
		)
		(fp_line
			(start 1.016 0.635)
			(end -1.016 0.635)
			(stroke
				(width 0.1)
				(type default)
			)
			(layer "B.Fab")
		)
		(fp_line
			(start -1.016 -0.635)
			(end 1.016 -0.635)
			(stroke
				(width 0.1)
				(type default)
			)
			(layer "B.Fab")
		)
		(fp_line
			(start 1.016 -0.635)
			(end 1.016 0.635)
			(stroke
				(width 0.1)
				(type default)
			)
			(layer "B.Fab")
		)
		(pad "1" smd rect
			(at 0.8382 0 90)
			(size 0.9652 1.3716)
			(layers "B.Cu" "B.Mask" "B.Paste")
			(net "XP5R0V_MAC")
		)
		(pad "2" smd rect
			(at -0.8382 0 90)
			(size 0.9652 1.3716)
			(layers "B.Cu" "B.Mask" "B.Paste")
			(net "SG")
		)
		(zone
			(layer "B.Cu")
			(hatch none 0.5)
			(connect_pads
				(clearance 0)
			)
			(min_thickness 0.25)
			(keepout
				(tracks allowed)
				(vias not_allowed)
				(pads allowed)
				(copperpour not_allowed)
				(footprints allowed)
			)
			(placement
				(enabled no)
				(sheetname "")
			)
			(fill
				(thermal_gap 0.5)
				(thermal_bridge_width 0.5)
				(island_removal_mode 0)
			)
			(polygon
				(pts
					(xy 78.359 -72.9234) (xy 79.629 -72.9234) (xy 79.629 -73.3806) (xy 78.359 -73.3806)
				)
			)
		)
	)
)
